(kicad_pcb
	(version 20241229)
	(generator "pcbnew")
	(generator_version "9.0")
	(general
		(thickness 1.62)
		(legacy_teardrops no)
	)
	(paper "A3")
	(title_block
		(title "COM Express 7 Baseboard")
		(date "2025-02-04")
		(rev "1.1.2")
		(company "Antmicro Ltd")
		(comment 1 "www.antmicro.com")
		(comment 9 "footprints 237-242 of 802")
	)
	(layers
		(0 "F.Cu" signal)
		(4 "In1.Cu" signal)
		(6 "In2.Cu" signal)
		(8 "In3.Cu" signal)
		(10 "In4.Cu" signal)
		(12 "In5.Cu" signal)
		(14 "In6.Cu" signal)
		(2 "B.Cu" signal)
		(9 "F.Adhes" user "F.Adhesive")
		(11 "B.Adhes" user "B.Adhesive")
		(13 "F.Paste" user)
		(15 "B.Paste" user)
		(5 "F.SilkS" user "F.Silkscreen")
		(7 "B.SilkS" user "B.Silkscreen")
		(1 "F.Mask" user)
		(3 "B.Mask" user)
		(17 "Dwgs.User" user "User.Drawings")
		(19 "Cmts.User" user "User.Comments")
		(21 "Eco1.User" user "User.Eco1")
		(23 "Eco2.User" user "User.Eco2")
		(25 "Edge.Cuts" user)
		(27 "Margin" user)
		(31 "F.CrtYd" user "F.Courtyard")
		(29 "B.CrtYd" user "B.Courtyard")
		(35 "F.Fab" user)
		(33 "B.Fab" user)
	)
	(footprint "antmicro-footprints:C_0402_1005Metric"
		(layer "F.Cu")
		(at 234.970708 75.76)
		(descr "Capacitor SMD 0402")
		(tags "capacitor SMD 0402")
		(property "Reference" "C92"
			(at -3.05 0.45 0)
			(layer "F.SilkS")
			(effects
				(font
					(size 0.7 0.7)
					(thickness 0.15)
				)
				(justify left bottom)
			)
		)
		(property "Value" "C_100n_0402"
			(at -1.022927 2.155213 0)
			(layer "F.Fab")
			(effects
				(font
					(size 0.7 0.7)
					(thickness 0.15)
				)
				(justify left bottom)
			)
		)
		(property "Datasheet" "https://www.murata.com/products/productdetail?partno=GRM155R61H104KE14%23"
			(at 0 0 0)
			(layer "F.Fab")
			(hide yes)
			(effects
				(font
					(size 1.27 1.27)
					(thickness 0.15)
				)
			)
		)
		(property "Author" "Antmicro"
			(at 0 0 0)
			(layer "F.Fab")
			(hide yes)
			(effects
				(font
					(size 1 1)
					(thickness 0.15)
				)
			)
		)
		(property "Dielectric" "X5R"
			(at 0 0 0)
			(layer "F.Fab")
			(hide yes)
			(effects
				(font
					(size 1 1)
					(thickness 0.15)
				)
			)
		)
		(property "License" "Apache-2.0"
			(at 0 0 0)
			(layer "F.Fab")
			(hide yes)
			(effects
				(font
					(size 1 1)
					(thickness 0.15)
				)
			)
		)
		(property "MPN" "GRM155R61H104KE14D"
			(at 0 0 0)
			(layer "F.Fab")
			(hide yes)
			(effects
				(font
					(size 1 1)
					(thickness 0.15)
				)
			)
		)
		(property "Manufacturer" "Murata"
			(at 0 0 0)
			(layer "F.Fab")
			(hide yes)
			(effects
				(font
					(size 1 1)
					(thickness 0.15)
				)
			)
		)
		(property "Public" "False"
			(at 0 0 0)
			(layer "F.Fab")
			(hide yes)
			(effects
				(font
					(size 1 1)
					(thickness 0.15)
				)
			)
		)
		(property "Val" "100n"
			(at 0 0 0)
			(layer "F.Fab")
			(hide yes)
			(effects
				(font
					(size 1 1)
					(thickness 0.15)
				)
			)
		)
		(property "Voltage" "50V"
			(at 0 0 0)
			(layer "F.Fab")
			(hide yes)
			(effects
				(font
					(size 1 1)
					(thickness 0.15)
				)
			)
		)
		(sheetname "Misc")
		(sheetfile "misc.kicad_sch")
		(attr smd)
		(fp_rect
			(start -0.925 -0.47)
			(end 0.925 0.47)
			(stroke
				(width 0.05)
				(type default)
			)
			(fill no)
			(layer "F.CrtYd")
		)
		(fp_line
			(start -0.494 -0.25)
			(end 0.504 -0.25)
			(stroke
				(width 0.15)
				(type solid)
			)
			(layer "F.Fab")
		)
		(fp_line
			(start -0.494 0.248)
			(end -0.494 -0.25)
			(stroke
				(width 0.15)
				(type solid)
			)
			(layer "F.Fab")
		)
		(fp_line
			(start 0.504 -0.25)
			(end 0.504 0.248)
			(stroke
				(width 0.15)
				(type solid)
			)
			(layer "F.Fab")
		)
		(fp_line
			(start 0.504 0.248)
			(end -0.494 0.248)
			(stroke
				(width 0.15)
				(type solid)
			)
			(layer "F.Fab")
		)
		(pad "1" smd roundrect
			(at -0.48 0)
			(size 0.59 0.64)
			(layers "F.Cu" "F.Mask" "F.Paste")
			(roundrect_rratio 0.25)
			(net 1 "GND")
			(pintype "passive")
			(teardrops
				(best_length_ratio 0.2)
				(max_length 1)
				(best_width_ratio 0.9)
				(max_width 2)
				(curved_edges yes)
				(filter_ratio 0.9)
				(enabled yes)
				(allow_two_segments yes)
				(prefer_zone_connections yes)
			)
		)
		(pad "2" smd roundrect
			(at 0.48 0)
			(size 0.59 0.64)
			(layers "F.Cu" "F.Mask" "F.Paste")
			(roundrect_rratio 0.25)
			(net 52 "+5V")
			(pintype "passive")
			(teardrops
				(best_length_ratio 0.2)
				(max_length 1)
				(best_width_ratio 0.9)
				(max_width 2)
				(curved_edges yes)
				(filter_ratio 0.9)
				(enabled yes)
				(allow_two_segments yes)
				(prefer_zone_connections yes)
			)
		)
	)
	(footprint "antmicro-footprints:R_0402_1005Metric"
		(layer "F.Cu")
		(at 208.939 78.11 180)
		(descr "Resistor SMD 0402")
		(tags "resistor SMD 0402")
		(property "Reference" "R180"
			(at -1.511 -1.4 0)
			(layer "F.SilkS")
			(effects
				(font
					(size 0.7 0.7)
					(thickness 0.15)
				)
				(justify right bottom)
			)
		)
		(property "Value" "R_1k_0402"
			(at -1.011843 1.772047 0)
			(layer "F.Fab")
			(effects
				(font
					(size 0.7 0.7)
					(thickness 0.15)
				)
				(justify right bottom)
			)
		)
		(property "Datasheet" "https://www.bourns.com/docs/product-datasheets/cr.pdf"
			(at 0 0 180)
			(layer "F.Fab")
			(hide yes)
			(effects
				(font
					(size 1.27 1.27)
					(thickness 0.15)
				)
			)
		)
		(property "Author" "Antmicro"
			(at 417.878 156.22 0)
			(layer "F.Fab")
			(hide yes)
			(effects
				(font
					(size 1 1)
					(thickness 0.15)
				)
			)
		)
		(property "License" "Apache-2.0"
			(at 417.878 156.22 0)
			(layer "F.Fab")
			(hide yes)
			(effects
				(font
					(size 1 1)
					(thickness 0.15)
				)
			)
		)
		(property "MPN" "CR0402-FX-1001GLF"
			(at 417.878 156.22 0)
			(layer "F.Fab")
			(hide yes)
			(effects
				(font
					(size 1 1)
					(thickness 0.15)
				)
			)
		)
		(property "Manufacturer" "Bourns"
			(at 417.878 156.22 0)
			(layer "F.Fab")
			(hide yes)
			(effects
				(font
					(size 1 1)
					(thickness 0.15)
				)
			)
		)
		(property "Public" "False"
			(at 417.878 156.22 0)
			(layer "F.Fab")
			(hide yes)
			(effects
				(font
					(size 1 1)
					(thickness 0.15)
				)
			)
		)
		(property "Tolerance" "1%"
			(at 417.878 156.22 0)
			(layer "F.Fab")
			(hide yes)
			(effects
				(font
					(size 1 1)
					(thickness 0.15)
				)
			)
		)
		(property "Val" "1k"
			(at 417.878 156.22 0)
			(layer "F.Fab")
			(hide yes)
			(effects
				(font
					(size 1 1)
					(thickness 0.15)
				)
			)
		)
		(sheetname "Com Express 7 MGMT")
		(sheetfile "com_express_7_mgmt.kicad_sch")
		(attr smd)
		(fp_rect
			(start -0.925 -0.47)
			(end 0.925 0.47)
			(stroke
				(width 0.05)
				(type default)
			)
			(fill no)
			(layer "F.CrtYd")
		)
		(fp_rect
			(start -0.5 -0.25)
			(end 0.5 0.25)
			(stroke
				(width 0.15)
				(type solid)
			)
			(fill no)
			(layer "F.Fab")
		)
		(pad "1" smd roundrect
			(at -0.48 0 180)
			(size 0.59 0.64)
			(layers "F.Cu" "F.Mask" "F.Paste")
			(roundrect_rratio 0.25)
			(net 310 "/Com Express 7 MGMT/~{BIOS_DIS0}")
			(pintype "passive")
			(teardrops
				(best_length_ratio 0.2)
				(max_length 1)
				(best_width_ratio 0.9)
				(max_width 2)
				(curved_edges yes)
				(filter_ratio 0.9)
				(enabled yes)
				(allow_two_segments yes)
				(prefer_zone_connections yes)
			)
		)
		(pad "2" smd roundrect
			(at 0.48 0 180)
			(size 0.59 0.64)
			(layers "F.Cu" "F.Mask" "F.Paste")
			(roundrect_rratio 0.25)
			(net 525 "Net-(J14-Pad2)")
			(pintype "passive")
			(teardrops
				(best_length_ratio 0.2)
				(max_length 1)
				(best_width_ratio 0.9)
				(max_width 2)
				(curved_edges yes)
				(filter_ratio 0.9)
				(enabled yes)
				(allow_two_segments yes)
				(prefer_zone_connections yes)
			)
		)
	)
	(footprint "antmicro-footprints:R_0402_1005Metric"
		(layer "F.Cu")
		(at 121.4 147.361 90)
		(descr "Resistor SMD 0402")
		(tags "resistor SMD 0402")
		(property "Reference" "R218"
			(at -3.749 0.45 90)
			(layer "F.SilkS")
			(effects
				(font
					(size 0.7 0.7)
					(thickness 0.15)
				)
				(justify left bottom)
			)
		)
		(property "Value" "R_0R_0402"
			(at -1.011843 1.772047 90)
			(layer "F.Fab")
			(effects
				(font
					(size 0.7 0.7)
					(thickness 0.15)
				)
				(justify left bottom)
			)
		)
		(property "Datasheet" "https://industrial.panasonic.com/cdbs/www-data/pdf/RDA0000/AOA0000C301.pdf"
			(at 0 0 90)
			(layer "F.Fab")
			(hide yes)
			(effects
				(font
					(size 1.27 1.27)
					(thickness 0.15)
				)
			)
		)
		(property "Author" "Antmicro"
			(at 268.761 25.961 0)
			(layer "F.Fab")
			(hide yes)
			(effects
				(font
					(size 1 1)
					(thickness 0.15)
				)
			)
		)
		(property "Current" "1A"
			(at 268.761 25.961 0)
			(layer "F.Fab")
			(hide yes)
			(effects
				(font
					(size 1 1)
					(thickness 0.15)
				)
			)
		)
		(property "License" "Apache-2.0"
			(at 268.761 25.961 0)
			(layer "F.Fab")
			(hide yes)
			(effects
				(font
					(size 1 1)
					(thickness 0.15)
				)
			)
		)
		(property "MPN" "ERJ2GE0R00X"
			(at 268.761 25.961 0)
			(layer "F.Fab")
			(hide yes)
			(effects
				(font
					(size 1 1)
					(thickness 0.15)
				)
			)
		)
		(property "Manufacturer" "Panasonic"
			(at 268.761 25.961 0)
			(layer "F.Fab")
			(hide yes)
			(effects
				(font
					(size 1 1)
					(thickness 0.15)
				)
			)
		)
		(property "Public" "False"
			(at 268.761 25.961 0)
			(layer "F.Fab")
			(hide yes)
			(effects
				(font
					(size 1 1)
					(thickness 0.15)
				)
			)
		)
		(property "Tolerance" ""
			(at 268.761 25.961 0)
			(layer "F.Fab")
			(hide yes)
			(effects
				(font
					(size 1 1)
					(thickness 0.15)
				)
			)
		)
		(property "Val" "0R"
			(at 268.761 25.961 0)
			(layer "F.Fab")
			(hide yes)
			(effects
				(font
					(size 1 1)
					(thickness 0.15)
				)
			)
		)
		(sheetname "PCIe redriver")
		(sheetfile "pcie_redriver.kicad_sch")
		(attr smd dnp)
		(fp_rect
			(start -0.925 -0.47)
			(end 0.925 0.47)
			(stroke
				(width 0.05)
				(type default)
			)
			(fill no)
			(layer "F.CrtYd")
		)
		(fp_rect
			(start -0.5 -0.25)
			(end 0.5 0.25)
			(stroke
				(width 0.15)
				(type solid)
			)
			(fill no)
			(layer "F.Fab")
		)
		(pad "1" smd roundrect
			(at -0.48 0 90)
			(size 0.59 0.64)
			(layers "F.Cu" "F.Mask" "F.Paste")
			(roundrect_rratio 0.25)
			(net 1 "GND")
			(pintype "passive")
			(teardrops
				(best_length_ratio 0.2)
				(max_length 1)
				(best_width_ratio 0.9)
				(max_width 2)
				(curved_edges yes)
				(filter_ratio 0.9)
				(enabled yes)
				(allow_two_segments yes)
				(prefer_zone_connections yes)
			)
		)
		(pad "2" smd roundrect
			(at 0.48 0 90)
			(size 0.59 0.64)
			(layers "F.Cu" "F.Mask" "F.Paste")
			(roundrect_rratio 0.25)
			(net 945 "/GPIO expander/GPIOEX5")
			(pintype "passive")
			(teardrops
				(best_length_ratio 0.2)
				(max_length 1)
				(best_width_ratio 0.9)
				(max_width 2)
				(curved_edges yes)
				(filter_ratio 0.9)
				(enabled yes)
				(allow_two_segments yes)
				(prefer_zone_connections yes)
			)
		)
	)
	(footprint "antmicro-footprints:R_0402_1005Metric"
		(layer "F.Cu")
		(at 252.664999 88.449999)
		(descr "Resistor SMD 0402")
		(tags "resistor SMD 0402")
		(property "Reference" "R148"
			(at -0.864999 0.440001 0)
			(layer "F.SilkS")
			(effects
				(font
					(size 0.7 0.7)
					(thickness 0.15)
				)
				(justify right bottom)
			)
		)
		(property "Value" "R_0R_0402"
			(at -1.011843 1.772047 0)
			(layer "F.Fab")
			(effects
				(font
					(size 0.7 0.7)
					(thickness 0.15)
				)
				(justify left bottom)
			)
		)
		(property "Datasheet" "https://industrial.panasonic.com/cdbs/www-data/pdf/RDA0000/AOA0000C301.pdf"
			(at 0 0 0)
			(layer "F.Fab")
			(hide yes)
			(effects
				(font
					(size 1.27 1.27)
					(thickness 0.15)
				)
			)
		)
		(property "Author" "Antmicro"
			(at 0 0 0)
			(layer "F.Fab")
			(hide yes)
			(effects
				(font
					(size 1 1)
					(thickness 0.15)
				)
			)
		)
		(property "Current" "1A"
			(at 0 0 0)
			(layer "F.Fab")
			(hide yes)
			(effects
				(font
					(size 1 1)
					(thickness 0.15)
				)
			)
		)
		(property "License" "Apache-2.0"
			(at 0 0 0)
			(layer "F.Fab")
			(hide yes)
			(effects
				(font
					(size 1 1)
					(thickness 0.15)
				)
			)
		)
		(property "MPN" "ERJ2GE0R00X"
			(at 0 0 0)
			(layer "F.Fab")
			(hide yes)
			(effects
				(font
					(size 1 1)
					(thickness 0.15)
				)
			)
		)
		(property "Manufacturer" "Panasonic"
			(at 0 0 0)
			(layer "F.Fab")
			(hide yes)
			(effects
				(font
					(size 1 1)
					(thickness 0.15)
				)
			)
		)
		(property "Public" "False"
			(at 0 0 0)
			(layer "F.Fab")
			(hide yes)
			(effects
				(font
					(size 1 1)
					(thickness 0.15)
				)
			)
		)
		(property "Tolerance" ""
			(at 0 0 0)
			(layer "F.Fab")
			(hide yes)
			(effects
				(font
					(size 1 1)
					(thickness 0.15)
				)
			)
		)
		(property "Val" "0R"
			(at 0 0 0)
			(layer "F.Fab")
			(hide yes)
			(effects
				(font
					(size 1 1)
					(thickness 0.15)
				)
			)
		)
		(sheetname "Misc")
		(sheetfile "misc.kicad_sch")
		(attr smd)
		(fp_rect
			(start -0.925 -0.47)
			(end 0.925 0.47)
			(stroke
				(width 0.05)
				(type default)
			)
			(fill no)
			(layer "F.CrtYd")
		)
		(fp_rect
			(start -0.5 -0.25)
			(end 0.5 0.25)
			(stroke
				(width 0.15)
				(type solid)
			)
			(fill no)
			(layer "F.Fab")
		)
		(pad "1" smd roundrect
			(at -0.48 0)
			(size 0.59 0.64)
			(layers "F.Cu" "F.Mask" "F.Paste")
			(roundrect_rratio 0.25)
			(net 74 "+1V0")
			(pintype "passive")
			(teardrops
				(best_length_ratio 0.2)
				(max_length 1)
				(best_width_ratio 0.9)
				(max_width 2)
				(curved_edges yes)
				(filter_ratio 0.9)
				(enabled yes)
				(allow_two_segments yes)
				(prefer_zone_connections yes)
			)
		)
		(pad "2" smd roundrect
			(at 0.48 0)
			(size 0.59 0.64)
			(layers "F.Cu" "F.Mask" "F.Paste")
			(roundrect_rratio 0.25)
			(net 590 "Net-(U24-+2.5V_{IN})")
			(pintype "passive")
			(teardrops
				(best_length_ratio 0.2)
				(max_length 1)
				(best_width_ratio 0.9)
				(max_width 2)
				(curved_edges yes)
				(filter_ratio 0.9)
				(enabled yes)
				(allow_two_segments yes)
				(prefer_zone_connections yes)
			)
		)
	)
	(footprint "antmicro-footprints:R_0402_1005Metric"
		(layer "F.Cu")
		(at 112.1 139.96 180)
		(descr "Resistor SMD 0402")
		(tags "resistor SMD 0402")
		(property "Reference" "R321"
			(at -3.65 -0.45 0)
			(layer "F.SilkS")
			(effects
				(font
					(size 0.7 0.7)
					(thickness 0.15)
				)
				(justify right bottom)
			)
		)
		(property "Value" "R_10k_0402"
			(at -1.011843 1.772047 0)
			(layer "F.Fab")
			(effects
				(font
					(size 0.7 0.7)
					(thickness 0.15)
				)
				(justify right bottom)
			)
		)
		(property "Datasheet" "https://www.bourns.com/docs/product-datasheets/cr.pdf"
			(at 0 0 180)
			(layer "F.Fab")
			(hide yes)
			(effects
				(font
					(size 1.27 1.27)
					(thickness 0.15)
				)
			)
		)
		(property "Author" "Antmicro"
			(at 224.2 279.92 0)
			(layer "F.Fab")
			(hide yes)
			(effects
				(font
					(size 1 1)
					(thickness 0.15)
				)
			)
		)
		(property "License" "Apache-2.0"
			(at 224.2 279.92 0)
			(layer "F.Fab")
			(hide yes)
			(effects
				(font
					(size 1 1)
					(thickness 0.15)
				)
			)
		)
		(property "MPN" "CR0402-FX-1002GLF"
			(at 224.2 279.92 0)
			(layer "F.Fab")
			(hide yes)
			(effects
				(font
					(size 1 1)
					(thickness 0.15)
				)
			)
		)
		(property "Manufacturer" "Bourns"
			(at 224.2 279.92 0)
			(layer "F.Fab")
			(hide yes)
			(effects
				(font
					(size 1 1)
					(thickness 0.15)
				)
			)
		)
		(property "Public" "False"
			(at 224.2 279.92 0)
			(layer "F.Fab")
			(hide yes)
			(effects
				(font
					(size 1 1)
					(thickness 0.15)
				)
			)
		)
		(property "Tolerance" "1%"
			(at 224.2 279.92 0)
			(layer "F.Fab")
			(hide yes)
			(effects
				(font
					(size 1 1)
					(thickness 0.15)
				)
			)
		)
		(property "Val" "10k"
			(at 224.2 279.92 0)
			(layer "F.Fab")
			(hide yes)
			(effects
				(font
					(size 1 1)
					(thickness 0.15)
				)
			)
		)
		(sheetname "SD card")
		(sheetfile "sd_card.kicad_sch")
		(attr smd)
		(fp_rect
			(start -0.925 -0.47)
			(end 0.925 0.47)
			(stroke
				(width 0.05)
				(type default)
			)
			(fill no)
			(layer "F.CrtYd")
		)
		(fp_rect
			(start -0.5 -0.25)
			(end 0.5 0.25)
			(stroke
				(width 0.15)
				(type solid)
			)
			(fill no)
			(layer "F.Fab")
		)
		(pad "1" smd roundrect
			(at -0.48 0 180)
			(size 0.59 0.64)
			(layers "F.Cu" "F.Mask" "F.Paste")
			(roundrect_rratio 0.25)
			(net 531 "/Com Express 7 Interfaces/SD_CD")
			(pintype "passive")
			(teardrops
				(best_length_ratio 0.2)
				(max_length 1)
				(best_width_ratio 0.9)
				(max_width 2)
				(curved_edges yes)
				(filter_ratio 0.9)
				(enabled yes)
				(allow_two_segments yes)
				(prefer_zone_connections yes)
			)
		)
		(pad "2" smd roundrect
			(at 0.48 0 180)
			(size 0.59 0.64)
			(layers "F.Cu" "F.Mask" "F.Paste")
			(roundrect_rratio 0.25)
			(net 2 "+3V3")
			(pintype "passive")
			(teardrops
				(best_length_ratio 0.2)
				(max_length 1)
				(best_width_ratio 0.9)
				(max_width 2)
				(curved_edges yes)
				(filter_ratio 0.9)
				(enabled yes)
				(allow_two_segments yes)
				(prefer_zone_connections yes)
			)
		)
	)
	(footprint "antmicro-footprints:R_0402_1005Metric"
		(layer "F.Cu")
		(at 209.38 127.82 180)
		(descr "Resistor SMD 0402")
		(tags "resistor SMD 0402")
		(property "Reference" "R192"
			(at 0.83 -0.39 0)
			(layer "F.SilkS")
			(effects
				(font
					(size 0.7 0.7)
					(thickness 0.15)
				)
				(justify right bottom)
			)
		)
		(property "Value" "R_0R_0402"
			(at -1.011843 1.772047 0)
			(layer "F.Fab")
			(effects
				(font
					(size 0.7 0.7)
					(thickness 0.15)
				)
				(justify right bottom)
			)
		)
		(property "Datasheet" "https://industrial.panasonic.com/cdbs/www-data/pdf/RDA0000/AOA0000C301.pdf"
			(at 0 0 180)
			(layer "F.Fab")
			(hide yes)
			(effects
				(font
					(size 1.27 1.27)
					(thickness 0.15)
				)
			)
		)
		(property "Author" "Antmicro"
			(at 418.76 255.64 0)
			(layer "F.Fab")
			(hide yes)
			(effects
				(font
					(size 1 1)
					(thickness 0.15)
				)
			)
		)
		(property "Current" "1A"
			(at 418.76 255.64 0)
			(layer "F.Fab")
			(hide yes)
			(effects
				(font
					(size 1 1)
					(thickness 0.15)
				)
			)
		)
		(property "License" "Apache-2.0"
			(at 418.76 255.64 0)
			(layer "F.Fab")
			(hide yes)
			(effects
				(font
					(size 1 1)
					(thickness 0.15)
				)
			)
		)
		(property "MPN" "ERJ2GE0R00X"
			(at 418.76 255.64 0)
			(layer "F.Fab")
			(hide yes)
			(effects
				(font
					(size 1 1)
					(thickness 0.15)
				)
			)
		)
		(property "Manufacturer" "Panasonic"
			(at 418.76 255.64 0)
			(layer "F.Fab")
			(hide yes)
			(effects
				(font
					(size 1 1)
					(thickness 0.15)
				)
			)
		)
		(property "Public" "False"
			(at 418.76 255.64 0)
			(layer "F.Fab")
			(hide yes)
			(effects
				(font
					(size 1 1)
					(thickness 0.15)
				)
			)
		)
		(property "Tolerance" ""
			(at 418.76 255.64 0)
			(layer "F.Fab")
			(hide yes)
			(effects
				(font
					(size 1 1)
					(thickness 0.15)
				)
			)
		)
		(property "Val" "0R"
			(at 418.76 255.64 0)
			(layer "F.Fab")
			(hide yes)
			(effects
				(font
					(size 1 1)
					(thickness 0.15)
				)
			)
		)
		(sheetname "PCIe misc")
		(sheetfile "pcie_misc.kicad_sch")
		(attr smd)
		(fp_rect
			(start -0.925 -0.47)
			(end 0.925 0.47)
			(stroke
				(width 0.05)
				(type default)
			)
			(fill no)
			(layer "F.CrtYd")
		)
		(fp_rect
			(start -0.5 -0.25)
			(end 0.5 0.25)
			(stroke
				(width 0.15)
				(type solid)
			)
			(fill no)
			(layer "F.Fab")
		)
		(pad "1" smd roundrect
			(at -0.48 0 180)
			(size 0.59 0.64)
			(layers "F.Cu" "F.Mask" "F.Paste")
			(roundrect_rratio 0.25)
			(net 611 "/PCIe misc/DIF0+")
			(pintype "passive")
			(teardrops
				(best_length_ratio 0.2)
				(max_length 1)
				(best_width_ratio 0.9)
				(max_width 2)
				(curved_edges yes)
				(filter_ratio 0.9)
				(enabled yes)
				(allow_two_segments yes)
				(prefer_zone_connections yes)
			)
		)
		(pad "2" smd roundrect
			(at 0.48 0 180)
			(size 0.59 0.64)
			(layers "F.Cu" "F.Mask" "F.Paste")
			(roundrect_rratio 0.25)
			(net 231 "/M.2 key M #1/PCIE_{REF}.CK+")
			(pintype "passive")
			(teardrops
				(best_length_ratio 0.2)
				(max_length 1)
				(best_width_ratio 0.9)
				(max_width 2)
				(curved_edges yes)
				(filter_ratio 0.9)
				(enabled yes)
				(allow_two_segments yes)
				(prefer_zone_connections yes)
			)
		)
	)
)
